(kicad_pcb
	(version 20260206)
	(generator "pcbnew")
	(generator_version "10.0")
	(general
		(thickness 1.6)
		(legacy_teardrops no)
	)
	(paper "A4")
	(title_block
		(title "pdpb — Lightning_PDPB_BRD.brd")
		(comment 1 "Lightning (Wiwynn / Facebook NVMe JBOF) / footprints 780-786 of 1140")
	)
	(layers
		(0 "F.Cu" signal "TOP")
		(4 "In1.Cu" signal "L2GND")
		(6 "In2.Cu" signal "L3")
		(8 "In3.Cu" signal "L4VCC")
		(10 "In4.Cu" signal "L5VCC")
		(12 "In5.Cu" signal "L6")
		(14 "In6.Cu" signal "L7GND")
		(2 "B.Cu" signal "BOTTOM")
		(9 "F.Adhes" user "F.Adhesive")
		(11 "B.Adhes" user "B.Adhesive")
		(13 "F.Paste" user "Package Geometry/Pastemask Top")
		(15 "B.Paste" user "Package Geometry/Pastemask Bottom")
		(5 "F.SilkS" user "Ref Des/Silkscreen Top")
		(7 "B.SilkS" user "Ref Des/Silkscreen Bottom")
		(1 "F.Mask" user "Board Geometry/Soldermask Top")
		(3 "B.Mask" user "Board Geometry/Soldermask Bottom")
		(17 "Dwgs.User" user "User.Drawings")
		(19 "Cmts.User" user "User.Comments")
		(21 "Eco1.User" user "User.Eco1")
		(23 "Eco2.User" user "User.Eco2")
		(25 "Edge.Cuts" user "Board Geometry/Outline")
		(27 "Margin" user)
		(31 "F.CrtYd" user "Package Geometry/Place Bound Top")
		(29 "B.CrtYd" user "Package Geometry/Place Bound Bottom")
		(35 "F.Fab" user "Ref Des/Assembly Top")
		(33 "B.Fab" user "Ref Des/Assembly Bottom")
	)
	(footprint ""
		(layer "F.Cu")
		(at 209.296 -400.177 180)
		(property "Reference" "Q9"
			(at 0 0 180)
			(layer "F.SilkS")
			(hide yes)
			(effects
				(font
					(size 1.27 1.27)
				)
			)
		)
		(property "Value" "2N7002A-7-GP"
			(at 0.127 -8.9662 180)
			(unlocked yes)
			(layer "F.Fab")
			(hide yes)
			(effects
				(font
					(size 1.016 1.016)
					(thickness 0.1524)
				)
			)
		)
		(property "Device Type" "SOT23DGS2D4H48"
			(at 0.127 -10.4902 180)
			(unlocked yes)
			(layer "F.Fab")
			(hide yes)
			(effects
				(font
					(size 1.016 1.016)
					(thickness 0.1524)
				)
			)
		)
		(duplicate_pad_numbers_are_jumpers no)
		(fp_line
			(start 1.651 1.778)
			(end 1.651 -1.778)
			(stroke
				(width 0.1524)
				(type default)
			)
			(layer "F.SilkS")
		)
		(fp_line
			(start 1.651 -1.778)
			(end -1.651 -1.778)
			(stroke
				(width 0.1524)
				(type default)
			)
			(layer "F.SilkS")
		)
		(fp_line
			(start -1.651 1.778)
			(end 1.651 1.778)
			(stroke
				(width 0.1524)
				(type default)
			)
			(layer "F.SilkS")
		)
		(fp_line
			(start -1.651 -1.778)
			(end -1.651 1.778)
			(stroke
				(width 0.1524)
				(type default)
			)
			(layer "F.SilkS")
		)
		(fp_poly
			(pts
				(xy -1.778 1.8796) (xy -1.778 -1.8796) (xy 1.778 -1.8796) (xy 1.778 1.8796)
			)
			(stroke
				(width 0)
				(type default)
			)
			(fill no)
			(layer "F.CrtYd")
		)
		(fp_poly
			(pts
				(xy -1.778 1.8796) (xy -1.778 -1.8796) (xy 1.778 -1.8796) (xy 1.778 1.8796)
			)
			(stroke
				(width 0)
				(type default)
			)
			(fill no)
			(layer "F.Fab")
		)
		(pad "D" smd custom
			(at 0 -0.9525 180)
			(size 0.1905 0.1905)
			(layers "F.Cu" "F.Mask" "F.Paste")
			(net "SW_SSD1_R")
			(options
				(clearance outline)
				(anchor circle)
			)
			(primitives
				(gr_poly
					(pts
						(arc
							(start -0.1778 0.5715)
							(mid -0.321484 0.511984)
							(end -0.381 0.3683)
						)
						(arc
							(start -0.381 -0.3683)
							(mid -0.321484 -0.511984)
							(end -0.1778 -0.5715)
						)
						(arc
							(start 0.1778 -0.5715)
							(mid 0.321484 -0.511984)
							(end 0.381 -0.3683)
						)
						(arc
							(start 0.381 0.3683)
							(mid 0.321484 0.511984)
							(end 0.1778 0.5715)
						)
					)
					(width 0)
					(fill yes)
				)
			)
		)
		(pad "G" smd custom
			(at -0.98425 0.9525 180)
			(size 0.1905 0.1905)
			(layers "F.Cu" "F.Mask" "F.Paste")
			(net "SSD1_PWREN")
			(options
				(clearance outline)
				(anchor circle)
			)
			(primitives
				(gr_poly
					(pts
						(arc
							(start -0.1778 0.5715)
							(mid -0.321484 0.511984)
							(end -0.381 0.3683)
						)
						(arc
							(start -0.381 -0.3683)
							(mid -0.321484 -0.511984)
							(end -0.1778 -0.5715)
						)
						(arc
							(start 0.1778 -0.5715)
							(mid 0.321484 -0.511984)
							(end 0.381 -0.3683)
						)
						(arc
							(start 0.381 0.3683)
							(mid 0.321484 0.511984)
							(end 0.1778 0.5715)
						)
					)
					(width 0)
					(fill yes)
				)
			)
		)
		(pad "S" smd custom
			(at 0.98425 0.9525 180)
			(size 0.1905 0.1905)
			(layers "F.Cu" "F.Mask" "F.Paste")
			(net "GND")
			(options
				(clearance outline)
				(anchor circle)
			)
			(primitives
				(gr_poly
					(pts
						(arc
							(start -0.1778 0.5715)
							(mid -0.321484 0.511984)
							(end -0.381 0.3683)
						)
						(arc
							(start -0.381 -0.3683)
							(mid -0.321484 -0.511984)
							(end -0.1778 -0.5715)
						)
						(arc
							(start 0.1778 -0.5715)
							(mid 0.321484 -0.511984)
							(end 0.381 -0.3683)
						)
						(arc
							(start 0.381 0.3683)
							(mid 0.321484 0.511984)
							(end 0.1778 0.5715)
						)
					)
					(width 0)
					(fill yes)
				)
			)
		)
	)
	(footprint ""
		(layer "F.Cu")
		(at 234.061 -247.771158 -90)
		(property "Reference" "R9400"
			(at 0 0 270)
			(layer "F.SilkS")
			(hide yes)
			(effects
				(font
					(size 1.27 1.27)
				)
			)
		)
		(property "Value" "330R2F-GP"
			(at 0.064008 -3.993896 270)
			(unlocked yes)
			(layer "F.Fab")
			(hide yes)
			(effects
				(font
					(size 1.016 1.016)
					(thickness 0.1524)
				)
			)
		)
		(property "Device Type" "R402H16"
			(at 0.064008 -5.517896 270)
			(unlocked yes)
			(layer "F.Fab")
			(hide yes)
			(effects
				(font
					(size 1.016 1.016)
					(thickness 0.1524)
				)
			)
		)
		(duplicate_pad_numbers_are_jumpers no)
		(fp_line
			(start -0.508 -0.9398)
			(end -0.508 0.9398)
			(stroke
				(width 0.1524)
				(type default)
			)
			(layer "F.SilkS")
		)
		(fp_line
			(start 0.508 -0.9398)
			(end -0.508 -0.9398)
			(stroke
				(width 0.1524)
				(type default)
			)
			(layer "F.SilkS")
		)
		(fp_rect
			(start -0.508 0.9398)
			(end 0.508 -0.9398)
			(stroke
				(width 0)
				(type default)
			)
			(fill no)
			(layer "F.CrtYd")
		)
		(fp_rect
			(start -0.508 0.9398)
			(end 0.508 -0.9398)
			(stroke
				(width 0)
				(type default)
			)
			(fill no)
			(layer "F.Fab")
		)
		(pad "1" smd custom
			(at 0 -0.4445 270)
			(size 0.1397 0.1397)
			(layers "F.Cu" "F.Mask" "F.Paste")
			(net "P3V3")
			(options
				(clearance outline)
				(anchor circle)
			)
			(primitives
				(gr_poly
					(pts
						(arc
							(start -0.1778 -0.2794)
							(mid -0.249642 -0.249642)
							(end -0.2794 -0.1778)
						)
						(arc
							(start -0.2794 0.1778)
							(mid -0.249642 0.249642)
							(end -0.1778 0.2794)
						)
						(arc
							(start 0.1778 0.2794)
							(mid 0.249642 0.249642)
							(end 0.2794 0.1778)
						)
						(arc
							(start 0.2794 -0.1778)
							(mid 0.249642 -0.249642)
							(end 0.1778 -0.2794)
						)
					)
					(width 0)
					(fill yes)
				)
			)
		)
		(pad "2" smd custom
			(at 0 0.4445 270)
			(size 0.1397 0.1397)
			(layers "F.Cu" "F.Mask" "F.Paste")
			(net "DRV_ATTN_2")
			(options
				(clearance outline)
				(anchor circle)
			)
			(primitives
				(gr_poly
					(pts
						(arc
							(start -0.1778 -0.2794)
							(mid -0.249642 -0.249642)
							(end -0.2794 -0.1778)
						)
						(arc
							(start -0.2794 0.1778)
							(mid -0.249642 0.249642)
							(end -0.1778 0.2794)
						)
						(arc
							(start 0.1778 0.2794)
							(mid 0.249642 0.249642)
							(end 0.2794 0.1778)
						)
						(arc
							(start 0.2794 -0.1778)
							(mid 0.249642 -0.249642)
							(end 0.1778 -0.2794)
						)
					)
					(width 0)
					(fill yes)
				)
			)
		)
	)
	(footprint ""
		(layer "F.Cu")
		(at 94.615 -424.688)
		(property "Reference" "C9514"
			(at 0 0 0)
			(layer "F.SilkS")
			(hide yes)
			(effects
				(font
					(size 1.27 1.27)
				)
			)
		)
		(property "Value" "SCD1U16V2KX-3GP"
			(at 1.1811 -2.7051 0)
			(unlocked yes)
			(layer "F.Fab")
			(hide yes)
			(effects
				(font
					(size 1.016 1.016)
					(thickness 0.1524)
				)
			)
		)
		(property "Device Type" "C402H22"
			(at 1.1811 -4.2291 0)
			(unlocked yes)
			(layer "F.Fab")
			(hide yes)
			(effects
				(font
					(size 1.016 1.016)
					(thickness 0.1524)
				)
			)
		)
		(duplicate_pad_numbers_are_jumpers no)
		(fp_rect
			(start -0.4318 0.9525)
			(end 0.4318 -0.9525)
			(stroke
				(width 0)
				(type default)
			)
			(fill no)
			(layer "F.CrtYd")
		)
		(fp_rect
			(start -0.4318 0.9525)
			(end 0.4318 -0.9525)
			(stroke
				(width 0)
				(type default)
			)
			(fill no)
			(layer "F.Fab")
		)
		(pad "1" smd custom
			(at 0 -0.4445)
			(size 0.1524 0.1524)
			(layers "F.Cu" "F.Mask" "F.Paste")
			(net "VDD_DIFF_1")
			(options
				(clearance outline)
				(anchor circle)
			)
			(primitives
				(gr_poly
					(pts
						(arc
							(start 0.3048 -0.2032)
							(mid 0.275042 -0.275042)
							(end 0.2032 -0.3048)
						)
						(arc
							(start -0.2032 -0.3048)
							(mid -0.275042 -0.275042)
							(end -0.3048 -0.2032)
						)
						(arc
							(start -0.3048 0.2032)
							(mid -0.275042 0.275042)
							(end -0.2032 0.3048)
						)
						(arc
							(start 0.2032 0.3048)
							(mid 0.275042 0.275042)
							(end 0.3048 0.2032)
						)
					)
					(width 0)
					(fill yes)
				)
			)
		)
		(pad "2" smd custom
			(at 0 0.4445)
			(size 0.1524 0.1524)
			(layers "F.Cu" "F.Mask" "F.Paste")
			(net "GND")
			(options
				(clearance outline)
				(anchor circle)
			)
			(primitives
				(gr_poly
					(pts
						(arc
							(start 0.3048 -0.2032)
							(mid 0.275042 -0.275042)
							(end 0.2032 -0.3048)
						)
						(arc
							(start -0.2032 -0.3048)
							(mid -0.275042 -0.275042)
							(end -0.3048 -0.2032)
						)
						(arc
							(start -0.3048 0.2032)
							(mid -0.275042 0.275042)
							(end -0.2032 0.3048)
						)
						(arc
							(start 0.2032 0.3048)
							(mid 0.275042 0.275042)
							(end 0.3048 0.2032)
						)
					)
					(width 0)
					(fill yes)
				)
			)
		)
	)
	(footprint ""
		(layer "F.Cu")
		(at 18.50009 -52.900072)
		(property "Reference" "LED14"
			(at 0 0 0)
			(layer "F.SilkS")
			(hide yes)
			(effects
				(font
					(size 1.27 1.27)
				)
			)
		)
		(property "Value" "LED-RB-4-GP"
			(at 5.88899 1.80848 0)
			(unlocked yes)
			(layer "F.Fab")
			(hide yes)
			(effects
				(font
					(size 1.016 1.016)
					(thickness 0.1524)
				)
			)
		)
		(property "Device Type" "LED1613-4PH20"
			(at 5.88899 0.28448 0)
			(unlocked yes)
			(layer "F.Fab")
			(hide yes)
			(effects
				(font
					(size 1.016 1.016)
					(thickness 0.1524)
				)
			)
		)
		(duplicate_pad_numbers_are_jumpers no)
		(fp_line
			(start -1.4478 -0.9652)
			(end 1.4478 -0.9652)
			(stroke
				(width 0.1524)
				(type default)
			)
			(layer "F.SilkS")
		)
		(fp_line
			(start -1.4478 0.9652)
			(end -1.4478 -0.9652)
			(stroke
				(width 0.1524)
				(type default)
			)
			(layer "F.SilkS")
		)
		(fp_line
			(start -1.4478 0.9652)
			(end -1.4478 -0.9652)
			(stroke
				(width 0.508)
				(type default)
			)
			(layer "F.SilkS")
		)
		(fp_line
			(start 1.4478 -0.9652)
			(end 1.4478 0.9652)
			(stroke
				(width 0.1524)
				(type default)
			)
			(layer "F.SilkS")
		)
		(fp_line
			(start 1.4478 0.9652)
			(end -1.4478 0.9652)
			(stroke
				(width 0.1524)
				(type default)
			)
			(layer "F.SilkS")
		)
		(fp_rect
			(start -0.8001 0.6477)
			(end 0.8001 -0.6477)
			(stroke
				(width 0)
				(type default)
			)
			(fill no)
			(layer "F.CrtYd")
		)
		(fp_poly
			(pts
				(xy -1.7018 1.2192) (xy -1.7018 -0.06223) (xy -0.8001 -0.06223) (xy -0.8001 0.6477) (xy 0.8001 0.6477)
				(xy 0.8001 -0.6477) (xy -0.8001 -0.6477) (xy -0.8001 -0.0635) (xy -1.7018 -0.0635) (xy -1.7018 -1.2192)
				(xy 1.7018 -1.2192) (xy 1.7018 1.2192)
			)
			(stroke
				(width 0)
				(type default)
			)
			(fill no)
			(layer "F.CrtYd")
		)
		(fp_rect
			(start -1.7018 1.2192)
			(end 1.7018 -1.2192)
			(stroke
				(width 0)
				(type default)
			)
			(fill no)
			(layer "F.Fab")
		)
		(pad "1" smd rect
			(at -0.73025 0.4064)
			(size 0.9144 0.6096)
			(layers "F.Cu" "F.Mask" "F.Paste")
			(net "SSD_ACT_DR14_MOS_N")
		)
		(pad "2" smd rect
			(at -0.73025 -0.4064)
			(size 0.9144 0.6096)
			(layers "F.Cu" "F.Mask" "F.Paste")
			(net "ATTN_LED_DR14_MOS_N")
		)
		(pad "3" smd rect
			(at 0.73025 -0.4064)
			(size 0.9144 0.6096)
			(layers "F.Cu" "F.Mask" "F.Paste")
			(net "DRV_ATTN_14")
		)
		(pad "4" smd rect
			(at 0.73025 0.4064)
			(size 0.9144 0.6096)
			(layers "F.Cu" "F.Mask" "F.Paste")
			(net "DRV_ACT_14")
		)
	)
	(footprint ""
		(layer "F.Cu")
		(at 100.5078 -431.546 180)
		(property "Reference" "C9419"
			(at 0 0 180)
			(layer "F.SilkS")
			(hide yes)
			(effects
				(font
					(size 1.27 1.27)
				)
			)
		)
		(property "Value" "SCD1U16V2KX-3GP"
			(at 1.1811 -2.7051 180)
			(unlocked yes)
			(layer "F.Fab")
			(hide yes)
			(effects
				(font
					(size 1.016 1.016)
					(thickness 0.1524)
				)
			)
		)
		(property "Device Type" "C402H22"
			(at 1.1811 -4.2291 180)
			(unlocked yes)
			(layer "F.Fab")
			(hide yes)
			(effects
				(font
					(size 1.016 1.016)
					(thickness 0.1524)
				)
			)
		)
		(duplicate_pad_numbers_are_jumpers no)
		(fp_rect
			(start -0.4318 0.9525)
			(end 0.4318 -0.9525)
			(stroke
				(width 0)
				(type default)
			)
			(fill no)
			(layer "F.CrtYd")
		)
		(fp_rect
			(start -0.4318 0.9525)
			(end 0.4318 -0.9525)
			(stroke
				(width 0)
				(type default)
			)
			(fill no)
			(layer "F.Fab")
		)
		(pad "1" smd custom
			(at 0 -0.4445 180)
			(size 0.1524 0.1524)
			(layers "F.Cu" "F.Mask" "F.Paste")
			(net "VDD_DIFF_1")
			(options
				(clearance outline)
				(anchor circle)
			)
			(primitives
				(gr_poly
					(pts
						(arc
							(start 0.3048 -0.2032)
							(mid 0.275042 -0.275042)
							(end 0.2032 -0.3048)
						)
						(arc
							(start -0.2032 -0.3048)
							(mid -0.275042 -0.275042)
							(end -0.3048 -0.2032)
						)
						(arc
							(start -0.3048 0.2032)
							(mid -0.275042 0.275042)
							(end -0.2032 0.3048)
						)
						(arc
							(start 0.2032 0.3048)
							(mid 0.275042 0.275042)
							(end 0.3048 0.2032)
						)
					)
					(width 0)
					(fill yes)
				)
			)
		)
		(pad "2" smd custom
			(at 0 0.4445 180)
			(size 0.1524 0.1524)
			(layers "F.Cu" "F.Mask" "F.Paste")
			(net "GND")
			(options
				(clearance outline)
				(anchor circle)
			)
			(primitives
				(gr_poly
					(pts
						(arc
							(start 0.3048 -0.2032)
							(mid 0.275042 -0.275042)
							(end 0.2032 -0.3048)
						)
						(arc
							(start -0.2032 -0.3048)
							(mid -0.275042 -0.275042)
							(end -0.3048 -0.2032)
						)
						(arc
							(start -0.3048 0.2032)
							(mid -0.275042 0.275042)
							(end -0.2032 0.3048)
						)
						(arc
							(start 0.2032 0.3048)
							(mid 0.275042 0.275042)
							(end 0.3048 0.2032)
						)
					)
					(width 0)
					(fill yes)
				)
			)
		)
	)
	(footprint ""
		(layer "F.Cu")
		(at 82.931 -438.15 90)
		(property "Reference" "R9350"
			(at 0 0 90)
			(layer "F.SilkS")
			(hide yes)
			(effects
				(font
					(size 1.27 1.27)
				)
			)
		)
		(property "Value" "2D2R2F-GP"
			(at 0.064008 -3.993896 90)
			(unlocked yes)
			(layer "F.Fab")
			(hide yes)
			(effects
				(font
					(size 1.016 1.016)
					(thickness 0.1524)
				)
			)
		)
		(property "Device Type" "R402H16"
			(at 0.064008 -5.517896 90)
			(unlocked yes)
			(layer "F.Fab")
			(hide yes)
			(effects
				(font
					(size 1.016 1.016)
					(thickness 0.1524)
				)
			)
		)
		(duplicate_pad_numbers_are_jumpers no)
		(fp_line
			(start 0.508 -0.9398)
			(end -0.508 -0.9398)
			(stroke
				(width 0.1524)
				(type default)
			)
			(layer "F.SilkS")
		)
		(fp_line
			(start -0.508 -0.9398)
			(end -0.508 0.9398)
			(stroke
				(width 0.1524)
				(type default)
			)
			(layer "F.SilkS")
		)
		(fp_rect
			(start -0.508 0.9398)
			(end 0.508 -0.9398)
			(stroke
				(width 0)
				(type default)
			)
			(fill no)
			(layer "F.CrtYd")
		)
		(fp_rect
			(start -0.508 0.9398)
			(end 0.508 -0.9398)
			(stroke
				(width 0)
				(type default)
			)
			(fill no)
			(layer "F.Fab")
		)
		(pad "1" smd custom
			(at 0 -0.4445 90)
			(size 0.1397 0.1397)
			(layers "F.Cu" "F.Mask" "F.Paste")
			(net "VDD_DIFF_1")
			(options
				(clearance outline)
				(anchor circle)
			)
			(primitives
				(gr_poly
					(pts
						(arc
							(start -0.1778 -0.2794)
							(mid -0.249642 -0.249642)
							(end -0.2794 -0.1778)
						)
						(arc
							(start -0.2794 0.1778)
							(mid -0.249642 0.249642)
							(end -0.1778 0.2794)
						)
						(arc
							(start 0.1778 0.2794)
							(mid 0.249642 0.249642)
							(end 0.2794 0.1778)
						)
						(arc
							(start 0.2794 -0.1778)
							(mid 0.249642 -0.249642)
							(end 0.1778 -0.2794)
						)
					)
					(width 0)
					(fill yes)
				)
			)
		)
		(pad "2" smd custom
			(at 0 0.4445 90)
			(size 0.1397 0.1397)
			(layers "F.Cu" "F.Mask" "F.Paste")
			(net "VDDA_1")
			(options
				(clearance outline)
				(anchor circle)
			)
			(primitives
				(gr_poly
					(pts
						(arc
							(start -0.1778 -0.2794)
							(mid -0.249642 -0.249642)
							(end -0.2794 -0.1778)
						)
						(arc
							(start -0.2794 0.1778)
							(mid -0.249642 0.249642)
							(end -0.1778 0.2794)
						)
						(arc
							(start 0.1778 0.2794)
							(mid 0.249642 0.249642)
							(end 0.2794 0.1778)
						)
						(arc
							(start 0.2794 -0.1778)
							(mid 0.249642 -0.249642)
							(end 0.1778 -0.2794)
						)
					)
					(width 0)
					(fill yes)
				)
			)
		)
	)
	(footprint ""
		(layer "F.Cu")
		(at 234.061 -348.488 -90)
		(property "Reference" "R9893"
			(at 0 0 270)
			(layer "F.SilkS")
			(hide yes)
			(effects
				(font
					(size 1.27 1.27)
				)
			)
		)
		(property "Value" "1K82R2F-1-GP"
			(at 0.064008 -3.993896 270)
			(unlocked yes)
			(layer "F.Fab")
			(hide yes)
			(effects
				(font
					(size 1.016 1.016)
					(thickness 0.1524)
				)
			)
		)
		(property "Device Type" "R402H16"
			(at 0.064008 -5.517896 270)
			(unlocked yes)
			(layer "F.Fab")
			(hide yes)
			(effects
				(font
					(size 1.016 1.016)
					(thickness 0.1524)
				)
			)
		)
		(duplicate_pad_numbers_are_jumpers no)
		(fp_line
			(start -0.508 -0.9398)
			(end -0.508 0.9398)
			(stroke
				(width 0.1524)
				(type default)
			)
			(layer "F.SilkS")
		)
		(fp_line
			(start 0.508 -0.9398)
			(end -0.508 -0.9398)
			(stroke
				(width 0.1524)
				(type default)
			)
			(layer "F.SilkS")
		)
		(fp_rect
			(start -0.508 0.9398)
			(end 0.508 -0.9398)
			(stroke
				(width 0)
				(type default)
			)
			(fill no)
			(layer "F.CrtYd")
		)
		(fp_rect
			(start -0.508 0.9398)
			(end 0.508 -0.9398)
			(stroke
				(width 0)
				(type default)
			)
			(fill no)
			(layer "F.Fab")
		)
		(pad "1" smd custom
			(at 0 -0.4445 270)
			(size 0.1397 0.1397)
			(layers "F.Cu" "F.Mask" "F.Paste")
			(net "P12V")
			(options
				(clearance outline)
				(anchor circle)
			)
			(primitives
				(gr_poly
					(pts
						(arc
							(start -0.1778 -0.2794)
							(mid -0.249642 -0.249642)
							(end -0.2794 -0.1778)
						)
						(arc
							(start -0.2794 0.1778)
							(mid -0.249642 0.249642)
							(end -0.1778 0.2794)
						)
						(arc
							(start 0.1778 0.2794)
							(mid 0.249642 0.249642)
							(end 0.2794 0.1778)
						)
						(arc
							(start 0.2794 -0.1778)
							(mid 0.249642 -0.249642)
							(end 0.1778 -0.2794)
						)
					)
					(width 0)
					(fill yes)
				)
			)
		)
		(pad "2" smd custom
			(at 0 0.4445 270)
			(size 0.1397 0.1397)
			(layers "F.Cu" "F.Mask" "F.Paste")
			(net "DRV_ACT_1")
			(options
				(clearance outline)
				(anchor circle)
			)
			(primitives
				(gr_poly
					(pts
						(arc
							(start -0.1778 -0.2794)
							(mid -0.249642 -0.249642)
							(end -0.2794 -0.1778)
						)
						(arc
							(start -0.2794 0.1778)
							(mid -0.249642 0.249642)
							(end -0.1778 0.2794)
						)
						(arc
							(start 0.1778 0.2794)
							(mid 0.249642 0.249642)
							(end 0.2794 0.1778)
						)
						(arc
							(start 0.2794 -0.1778)
							(mid 0.249642 -0.249642)
							(end 0.1778 -0.2794)
						)
					)
					(width 0)
					(fill yes)
				)
			)
		)
	)
)
